(kicad_pcb
	(version 20260206)
	(generator "pcbnew")
	(generator_version "10.0")
	(general
		(thickness 1.6)
		(legacy_teardrops no)
	)
	(paper "A4")
	(title_block
		(title "04192023_DAF0TMB3IC0_F0TG_MB_C_brd_V02_OCP.brd")
		(comment 1 "Grand Teton / footprint 3975 of 8354 (U6014), pads 337-354 of 354")
	)
	(layers
		(0 "F.Cu" signal "TOP")
		(4 "In1.Cu" signal "GND")
		(6 "In2.Cu" signal "IN1")
		(8 "In3.Cu" signal "GND1")
		(10 "In4.Cu" signal "IN2")
		(12 "In5.Cu" signal "GND2")
		(14 "In6.Cu" signal "IN3")
		(16 "In7.Cu" signal "GND3")
		(18 "In8.Cu" signal "VCC")
		(20 "In9.Cu" signal "VCC1")
		(22 "In10.Cu" signal "GND4")
		(24 "In11.Cu" signal "IN4")
		(26 "In12.Cu" signal "GND5")
		(28 "In13.Cu" signal "IN5")
		(30 "In14.Cu" signal "GND6")
		(32 "In15.Cu" signal "IN6")
		(34 "In16.Cu" signal "GND7")
		(2 "B.Cu" signal "BOTTOM")
		(9 "F.Adhes" user "F.Adhesive")
		(11 "B.Adhes" user "B.Adhesive")
		(13 "F.Paste" user "Package Geometry/Pastemask Top")
		(15 "B.Paste" user "Package Geometry/Pastemask Bottom")
		(5 "F.SilkS" user "Ref Des/Silkscreen Top")
		(7 "B.SilkS" user "Ref Des/Silkscreen Bottom")
		(1 "F.Mask" user "Board Geometry/Soldermask Top")
		(3 "B.Mask" user "Board Geometry/Soldermask Bottom")
		(17 "Dwgs.User" user "User.Drawings")
		(19 "Cmts.User" user "User.Comments")
		(21 "Eco1.User" user "User.Eco1")
		(23 "Eco2.User" user "User.Eco2")
		(25 "Edge.Cuts" user "Board Geometry/Outline")
		(27 "Margin" user)
		(31 "F.CrtYd" user "Package Geometry/Place Bound Top")
		(29 "B.CrtYd" user "Package Geometry/Place Bound Bottom")
		(35 "F.Fab" user "Ref Des/Assembly Top")
		(33 "B.Fab" user "Ref Des/Assembly Bottom")
	)
	(footprint ""
		(layer "F.Cu")
		(at 56.46801 -387.342634)
		(property "Reference" "U6014"
			(at -6.735064 -7.919974 0)
			(unlocked yes)
			(layer "F.SilkS")
			(effects
				(font
					(size 0.7874 0.5842)
					(thickness 0.1524)
				)
				(justify left)
			)
		)
		(property "Value" ""
			(at 0 0 0)
			(layer "F.Fab")
			(effects
				(font
					(size 1.27 1.27)
				)
			)
		)
		(duplicate_pad_numbers_are_jumpers no)
		(pad "P10" smd circle
			(at 8.802624 -1.431798)
			(size 0.381 0.381)
			(layers "F.Cu" "F.Mask" "F.Paste")
			(net "P5E_CPU1_P0_TX_BUF_DN<15>")
		)
		(pad "P29" smd circle
			(at 8.802624 2.032254)
			(size 0.381 0.381)
			(layers "F.Cu" "F.Mask" "F.Paste")
			(net "P5E_CPU1_P0_RX_DN<15>")
		)
		(pad "R1" smd oval
			(at 8.64997 -3.938524)
			(size 0.254 0.3302)
			(layers "F.Cu" "F.Mask" "F.Paste")
			(net "P5E_CPU1_P0_RX_BUF_DP<15>")
		)
		(pad "R35" smd oval
			(at 8.64997 3.940048)
			(size 0.254 0.3302)
			(layers "F.Cu" "F.Mask" "F.Paste")
			(net "P5E_CPU1_P0_TX_C_DP<15>")
		)
		(pad "T4" smd circle
			(at 8.402574 -2.817368)
			(size 0.381 0.381)
			(layers "F.Cu" "F.Mask" "F.Paste")
			(net "GND")
		)
		(pad "T13" smd circle
			(at 8.402574 -0.79629)
			(size 0.3048 0.3048)
			(layers "F.Cu" "F.Mask" "F.Paste")
			(net "GND")
		)
		(pad "T17" smd circle
			(at 8.402574 -0.296164)
			(size 0.3048 0.3048)
			(layers "F.Cu" "F.Mask" "F.Paste")
			(net "P0V9_CPU1_RT0_2A")
		)
		(pad "T20" smd circle
			(at 8.402574 0.203708)
			(size 0.3048 0.3048)
			(layers "F.Cu" "F.Mask" "F.Paste")
			(net "P0V9_CPU1_RT0_2A")
		)
		(pad "T22" smd circle
			(at 8.402574 0.703834)
			(size 0.3048 0.3048)
			(layers "F.Cu" "F.Mask" "F.Paste")
			(net "GND")
		)
		(pad "T32" smd circle
			(at 8.402574 2.724912)
			(size 0.381 0.381)
			(layers "F.Cu" "F.Mask" "F.Paste")
			(net "GND")
		)
		(pad "U2" smd circle
			(at 8.349996 -3.41884)
			(size 0.3048 0.3048)
			(layers "F.Cu" "F.Mask" "F.Paste")
			(net "GND")
		)
		(pad "U34" smd circle
			(at 8.349996 3.420364)
			(size 0.3048 0.3048)
			(layers "F.Cu" "F.Mask" "F.Paste")
			(net "GND")
		)
		(pad "V1" smd oval
			(at 8.050022 -3.938524)
			(size 0.254 0.3302)
			(layers "F.Cu" "F.Mask" "F.Paste")
			(net "GND")
		)
		(pad "V35" smd oval
			(at 8.050022 3.940048)
			(size 0.254 0.3302)
			(layers "F.Cu" "F.Mask" "F.Paste")
			(net "GND")
		)
		(pad "W7" smd circle
			(at 8.002524 -2.12471)
			(size 0.381 0.381)
			(layers "F.Cu" "F.Mask" "F.Paste")
			(net "P5E_CPU1_P0_TX_BUF_DP<14>")
		)
		(pad "W26" smd circle
			(at 8.002524 1.339342)
			(size 0.381 0.381)
			(layers "F.Cu" "F.Mask" "F.Paste")
			(net "P5E_CPU1_P0_RX_DP<14>")
		)
		(pad "Y2" smd circle
			(at 7.750048 -3.41884)
			(size 0.3048 0.3048)
			(layers "F.Cu" "F.Mask" "F.Paste")
			(net "P5E_CPU1_P0_RX_BUF_DN<14>")
		)
		(pad "Y34" smd circle
			(at 7.750048 3.420364)
			(size 0.3048 0.3048)
			(layers "F.Cu" "F.Mask" "F.Paste")
			(net "P5E_CPU1_P0_TX_C_DN<14>")
		)
	)
)
